(kicad_pcb
	(version 20260206)
	(generator "pcbnew")
	(generator_version "10.0")
	(general
		(thickness 1.6)
		(legacy_teardrops no)
	)
	(paper "A4")
	(title_block
		(title "04192023_DAF0TMB3IC0_F0TG_MB_C_brd_V02_OCP.brd")
		(comment 1 "Grand Teton / footprint 2335 of 8354 (J69), pads 1-113 of 291")
	)
	(layers
		(0 "F.Cu" signal "TOP")
		(4 "In1.Cu" signal "GND")
		(6 "In2.Cu" signal "IN1")
		(8 "In3.Cu" signal "GND1")
		(10 "In4.Cu" signal "IN2")
		(12 "In5.Cu" signal "GND2")
		(14 "In6.Cu" signal "IN3")
		(16 "In7.Cu" signal "GND3")
		(18 "In8.Cu" signal "VCC")
		(20 "In9.Cu" signal "VCC1")
		(22 "In10.Cu" signal "GND4")
		(24 "In11.Cu" signal "IN4")
		(26 "In12.Cu" signal "GND5")
		(28 "In13.Cu" signal "IN5")
		(30 "In14.Cu" signal "GND6")
		(32 "In15.Cu" signal "IN6")
		(34 "In16.Cu" signal "GND7")
		(2 "B.Cu" signal "BOTTOM")
		(9 "F.Adhes" user "F.Adhesive")
		(11 "B.Adhes" user "B.Adhesive")
		(13 "F.Paste" user "Package Geometry/Pastemask Top")
		(15 "B.Paste" user "Package Geometry/Pastemask Bottom")
		(5 "F.SilkS" user "Ref Des/Silkscreen Top")
		(7 "B.SilkS" user "Ref Des/Silkscreen Bottom")
		(1 "F.Mask" user "Board Geometry/Soldermask Top")
		(3 "B.Mask" user "Board Geometry/Soldermask Bottom")
		(17 "Dwgs.User" user "User.Drawings")
		(19 "Cmts.User" user "User.Comments")
		(21 "Eco1.User" user "User.Eco1")
		(23 "Eco2.User" user "User.Eco2")
		(25 "Edge.Cuts" user "Board Geometry/Outline")
		(27 "Margin" user)
		(31 "F.CrtYd" user "Package Geometry/Place Bound Top")
		(29 "B.CrtYd" user "Package Geometry/Place Bound Bottom")
		(35 "F.Fab" user "Ref Des/Assembly Top")
		(33 "B.Fab" user "Ref Des/Assembly Bottom")
	)
	(footprint ""
		(layer "F.Cu")
		(at 421.962072 -255.560068 180)
		(property "Reference" "J69"
			(at 3.448304 81.947512 0)
			(unlocked yes)
			(layer "F.SilkS")
			(effects
				(font
					(size 0.7874 0.5842)
					(thickness 0.1524)
				)
			)
		)
		(property "Value" ""
			(at 0 0 180)
			(layer "F.Fab")
			(effects
				(font
					(size 1.27 1.27)
				)
			)
		)
		(duplicate_pad_numbers_are_jumpers no)
		(pad "1" smd rect
			(at -2.050034 -63.324994 90)
			(size 0.519938 1.4986)
			(layers "F.Cu" "F.Mask" "F.Paste")
			(net "P12V_MEM_CPU0")
		)
		(pad "2" smd rect
			(at -2.050034 -62.47511 90)
			(size 0.519938 1.4986)
			(layers "F.Cu" "F.Mask" "F.Paste")
			(net "Net_2347")
		)
		(pad "3" smd rect
			(at -2.050034 -61.624972 90)
			(size 0.519938 1.4986)
			(layers "F.Cu" "F.Mask" "F.Paste")
			(net "P3V3_AUX")
		)
		(pad "4" smd rect
			(at -2.050034 -60.775088 90)
			(size 0.519938 1.4986)
			(layers "F.Cu" "F.Mask" "F.Paste")
			(net "I3C_SPD_DDRH_CPU0_SCL")
		)
		(pad "5" smd rect
			(at -2.050034 -59.92495 90)
			(size 0.519938 1.4986)
			(layers "F.Cu" "F.Mask" "F.Paste")
			(net "I3C_SPD_DDRH_CPU0_SDA")
		)
		(pad "6" smd rect
			(at -2.050034 -59.075066 90)
			(size 0.519938 1.4986)
			(layers "F.Cu" "F.Mask" "F.Paste")
			(net "GND")
		)
		(pad "7" smd rect
			(at -2.050034 -58.224928 90)
			(size 0.519938 1.4986)
			(layers "F.Cu" "F.Mask" "F.Paste")
			(net "M_H_CPU0_SA_DQ<0>")
		)
		(pad "8" smd rect
			(at -2.050034 -57.375044 90)
			(size 0.519938 1.4986)
			(layers "F.Cu" "F.Mask" "F.Paste")
			(net "GND")
		)
		(pad "9" smd rect
			(at -2.050034 -56.524906 90)
			(size 0.519938 1.4986)
			(layers "F.Cu" "F.Mask" "F.Paste")
			(net "M_H_CPU0_SA_DQ<1>")
		)
		(pad "10" smd rect
			(at -2.050034 -55.675022 90)
			(size 0.519938 1.4986)
			(layers "F.Cu" "F.Mask" "F.Paste")
			(net "GND")
		)
		(pad "11" smd rect
			(at -2.050034 -54.824884 90)
			(size 0.519938 1.4986)
			(layers "F.Cu" "F.Mask" "F.Paste")
			(net "M_H_CPU0_SA_DQS_DP<0>")
		)
		(pad "12" smd rect
			(at -2.050034 -53.975 90)
			(size 0.519938 1.4986)
			(layers "F.Cu" "F.Mask" "F.Paste")
			(net "M_H_CPU0_SA_DQS_DN<0>")
		)
		(pad "13" smd rect
			(at -2.050034 -53.125116 90)
			(size 0.519938 1.4986)
			(layers "F.Cu" "F.Mask" "F.Paste")
			(net "GND")
		)
		(pad "14" smd rect
			(at -2.050034 -52.274978 90)
			(size 0.519938 1.4986)
			(layers "F.Cu" "F.Mask" "F.Paste")
			(net "M_H_CPU0_SA_DQ<4>")
		)
		(pad "15" smd rect
			(at -2.050034 -51.425094 90)
			(size 0.519938 1.4986)
			(layers "F.Cu" "F.Mask" "F.Paste")
			(net "GND")
		)
		(pad "16" smd rect
			(at -2.050034 -50.574956 90)
			(size 0.519938 1.4986)
			(layers "F.Cu" "F.Mask" "F.Paste")
			(net "M_H_CPU0_SA_DQ<5>")
		)
		(pad "17" smd rect
			(at -2.050034 -49.725072 90)
			(size 0.519938 1.4986)
			(layers "F.Cu" "F.Mask" "F.Paste")
			(net "GND")
		)
		(pad "18" smd rect
			(at -2.050034 -48.874934 90)
			(size 0.519938 1.4986)
			(layers "F.Cu" "F.Mask" "F.Paste")
			(net "M_H_CPU0_SA_DQ<8>")
		)
		(pad "19" smd rect
			(at -2.050034 -48.02505 90)
			(size 0.519938 1.4986)
			(layers "F.Cu" "F.Mask" "F.Paste")
			(net "GND")
		)
		(pad "20" smd rect
			(at -2.050034 -47.174912 90)
			(size 0.519938 1.4986)
			(layers "F.Cu" "F.Mask" "F.Paste")
			(net "M_H_CPU0_SA_DQ<9>")
		)
		(pad "21" smd rect
			(at -2.050034 -46.325028 90)
			(size 0.519938 1.4986)
			(layers "F.Cu" "F.Mask" "F.Paste")
			(net "GND")
		)
		(pad "22" smd rect
			(at -2.050034 -45.47489 90)
			(size 0.519938 1.4986)
			(layers "F.Cu" "F.Mask" "F.Paste")
			(net "M_H_CPU0_SA_DQS_DP<1>")
		)
		(pad "23" smd rect
			(at -2.050034 -44.625006 90)
			(size 0.519938 1.4986)
			(layers "F.Cu" "F.Mask" "F.Paste")
			(net "M_H_CPU0_SA_DQS_DN<1>")
		)
		(pad "24" smd rect
			(at -2.050034 -43.775122 90)
			(size 0.519938 1.4986)
			(layers "F.Cu" "F.Mask" "F.Paste")
			(net "GND")
		)
		(pad "25" smd rect
			(at -2.050034 -42.924984 90)
			(size 0.519938 1.4986)
			(layers "F.Cu" "F.Mask" "F.Paste")
			(net "M_H_CPU0_SA_DQ<12>")
		)
		(pad "26" smd rect
			(at -2.050034 -42.0751 90)
			(size 0.519938 1.4986)
			(layers "F.Cu" "F.Mask" "F.Paste")
			(net "GND")
		)
		(pad "27" smd rect
			(at -2.050034 -41.224962 90)
			(size 0.519938 1.4986)
			(layers "F.Cu" "F.Mask" "F.Paste")
			(net "M_H_CPU0_SA_DQ<13>")
		)
		(pad "28" smd rect
			(at -2.050034 -40.375078 90)
			(size 0.519938 1.4986)
			(layers "F.Cu" "F.Mask" "F.Paste")
			(net "GND")
		)
		(pad "29" smd rect
			(at -2.050034 -39.52494 90)
			(size 0.519938 1.4986)
			(layers "F.Cu" "F.Mask" "F.Paste")
			(net "M_H_CPU0_SA_DQ<16>")
		)
		(pad "30" smd rect
			(at -2.050034 -38.675056 90)
			(size 0.519938 1.4986)
			(layers "F.Cu" "F.Mask" "F.Paste")
			(net "GND")
		)
		(pad "31" smd rect
			(at -2.050034 -37.824918 90)
			(size 0.519938 1.4986)
			(layers "F.Cu" "F.Mask" "F.Paste")
			(net "M_H_CPU0_SA_DQ<17>")
		)
		(pad "32" smd rect
			(at -2.050034 -36.975034 90)
			(size 0.519938 1.4986)
			(layers "F.Cu" "F.Mask" "F.Paste")
			(net "GND")
		)
		(pad "33" smd rect
			(at -2.050034 -36.124896 90)
			(size 0.519938 1.4986)
			(layers "F.Cu" "F.Mask" "F.Paste")
			(net "M_H_CPU0_SA_DQS_DP<2>")
		)
		(pad "34" smd rect
			(at -2.050034 -35.275012 90)
			(size 0.519938 1.4986)
			(layers "F.Cu" "F.Mask" "F.Paste")
			(net "M_H_CPU0_SA_DQS_DN<2>")
		)
		(pad "35" smd rect
			(at -2.050034 -34.425128 90)
			(size 0.519938 1.4986)
			(layers "F.Cu" "F.Mask" "F.Paste")
			(net "GND")
		)
		(pad "36" smd rect
			(at -2.050034 -33.57499 90)
			(size 0.519938 1.4986)
			(layers "F.Cu" "F.Mask" "F.Paste")
			(net "M_H_CPU0_SA_DQ<20>")
		)
		(pad "37" smd rect
			(at -2.050034 -32.725106 90)
			(size 0.519938 1.4986)
			(layers "F.Cu" "F.Mask" "F.Paste")
			(net "GND")
		)
		(pad "38" smd rect
			(at -2.050034 -31.874968 90)
			(size 0.519938 1.4986)
			(layers "F.Cu" "F.Mask" "F.Paste")
			(net "M_H_CPU0_SA_DQ<21>")
		)
		(pad "39" smd rect
			(at -2.050034 -31.025084 90)
			(size 0.519938 1.4986)
			(layers "F.Cu" "F.Mask" "F.Paste")
			(net "GND")
		)
		(pad "40" smd rect
			(at -2.050034 -30.174946 90)
			(size 0.519938 1.4986)
			(layers "F.Cu" "F.Mask" "F.Paste")
			(net "M_H_CPU0_SA_DQ<24>")
		)
		(pad "41" smd rect
			(at -2.050034 -29.325062 90)
			(size 0.519938 1.4986)
			(layers "F.Cu" "F.Mask" "F.Paste")
			(net "GND")
		)
		(pad "42" smd rect
			(at -2.050034 -28.474924 90)
			(size 0.519938 1.4986)
			(layers "F.Cu" "F.Mask" "F.Paste")
			(net "M_H_CPU0_SA_DQ<25>")
		)
		(pad "43" smd rect
			(at -2.050034 -27.62504 90)
			(size 0.519938 1.4986)
			(layers "F.Cu" "F.Mask" "F.Paste")
			(net "GND")
		)
		(pad "44" smd rect
			(at -2.050034 -26.774902 90)
			(size 0.519938 1.4986)
			(layers "F.Cu" "F.Mask" "F.Paste")
			(net "M_H_CPU0_SA_DQS_DP<3>")
		)
		(pad "45" smd rect
			(at -2.050034 -25.925018 90)
			(size 0.519938 1.4986)
			(layers "F.Cu" "F.Mask" "F.Paste")
			(net "M_H_CPU0_SA_DQS_DN<3>")
		)
		(pad "46" smd rect
			(at -2.050034 -25.07488 90)
			(size 0.519938 1.4986)
			(layers "F.Cu" "F.Mask" "F.Paste")
			(net "GND")
		)
		(pad "47" smd rect
			(at -2.050034 -24.224996 90)
			(size 0.519938 1.4986)
			(layers "F.Cu" "F.Mask" "F.Paste")
			(net "M_H_CPU0_SA_DQ<28>")
		)
		(pad "48" smd rect
			(at -2.050034 -23.375112 90)
			(size 0.519938 1.4986)
			(layers "F.Cu" "F.Mask" "F.Paste")
			(net "GND")
		)
		(pad "49" smd rect
			(at -2.050034 -22.524974 90)
			(size 0.519938 1.4986)
			(layers "F.Cu" "F.Mask" "F.Paste")
			(net "M_H_CPU0_SA_DQ<29>")
		)
		(pad "50" smd rect
			(at -2.050034 -21.67509 90)
			(size 0.519938 1.4986)
			(layers "F.Cu" "F.Mask" "F.Paste")
			(net "GND")
		)
		(pad "51" smd rect
			(at -2.050034 -20.824952 90)
			(size 0.519938 1.4986)
			(layers "F.Cu" "F.Mask" "F.Paste")
			(net "M_H_CPU0_SA_CB<0>")
		)
		(pad "52" smd rect
			(at -2.050034 -19.975068 90)
			(size 0.519938 1.4986)
			(layers "F.Cu" "F.Mask" "F.Paste")
			(net "GND")
		)
		(pad "53" smd rect
			(at -2.050034 -19.12493 90)
			(size 0.519938 1.4986)
			(layers "F.Cu" "F.Mask" "F.Paste")
			(net "M_H_CPU0_SA_CB<1>")
		)
		(pad "54" smd rect
			(at -2.050034 -18.275046 90)
			(size 0.519938 1.4986)
			(layers "F.Cu" "F.Mask" "F.Paste")
			(net "GND")
		)
		(pad "55" smd rect
			(at -2.050034 -17.424908 90)
			(size 0.519938 1.4986)
			(layers "F.Cu" "F.Mask" "F.Paste")
			(net "M_H_CPU0_SA_DQS_DP<4>")
		)
		(pad "56" smd rect
			(at -2.050034 -16.575024 90)
			(size 0.519938 1.4986)
			(layers "F.Cu" "F.Mask" "F.Paste")
			(net "M_H_CPU0_SA_DQS_DN<4>")
		)
		(pad "57" smd rect
			(at -2.050034 -15.724886 90)
			(size 0.519938 1.4986)
			(layers "F.Cu" "F.Mask" "F.Paste")
			(net "GND")
		)
		(pad "58" smd rect
			(at -2.050034 -14.875002 90)
			(size 0.519938 1.4986)
			(layers "F.Cu" "F.Mask" "F.Paste")
			(net "M_H_CPU0_SA_CB<4>")
		)
		(pad "59" smd rect
			(at -2.050034 -14.025118 90)
			(size 0.519938 1.4986)
			(layers "F.Cu" "F.Mask" "F.Paste")
			(net "GND")
		)
		(pad "60" smd rect
			(at -2.050034 -13.17498 90)
			(size 0.519938 1.4986)
			(layers "F.Cu" "F.Mask" "F.Paste")
			(net "M_H_CPU0_SA_CB<5>")
		)
		(pad "61" smd rect
			(at -2.050034 -12.325096 90)
			(size 0.519938 1.4986)
			(layers "F.Cu" "F.Mask" "F.Paste")
			(net "GND")
		)
		(pad "62" smd rect
			(at -2.050034 -11.474958 90)
			(size 0.519938 1.4986)
			(layers "F.Cu" "F.Mask" "F.Paste")
			(net "M_H_CPU0_ALERT_N")
		)
		(pad "63" smd rect
			(at -2.050034 -10.625074 90)
			(size 0.519938 1.4986)
			(layers "F.Cu" "F.Mask" "F.Paste")
			(net "GND")
		)
		(pad "64" smd rect
			(at -2.050034 -9.774936 90)
			(size 0.519938 1.4986)
			(layers "F.Cu" "F.Mask" "F.Paste")
			(net "M_H_CPU0_SA_CS_N<0>")
		)
		(pad "65" smd rect
			(at -2.050034 -8.925052 90)
			(size 0.519938 1.4986)
			(layers "F.Cu" "F.Mask" "F.Paste")
			(net "GND")
		)
		(pad "66" smd rect
			(at -2.050034 -8.074914 90)
			(size 0.519938 1.4986)
			(layers "F.Cu" "F.Mask" "F.Paste")
			(net "M_H_CPU0_SA_CA<0>")
		)
		(pad "67" smd rect
			(at -2.050034 -7.22503 90)
			(size 0.519938 1.4986)
			(layers "F.Cu" "F.Mask" "F.Paste")
			(net "GND")
		)
		(pad "68" smd rect
			(at -2.050034 -6.374892 90)
			(size 0.519938 1.4986)
			(layers "F.Cu" "F.Mask" "F.Paste")
			(net "M_H_CPU0_SA_CA<2>")
		)
		(pad "69" smd rect
			(at -2.050034 -5.525008 90)
			(size 0.519938 1.4986)
			(layers "F.Cu" "F.Mask" "F.Paste")
			(net "GND")
		)
		(pad "70" smd rect
			(at -2.050034 -4.675124 90)
			(size 0.519938 1.4986)
			(layers "F.Cu" "F.Mask" "F.Paste")
			(net "M_H_CPU0_SA_CA<4>")
		)
		(pad "71" smd rect
			(at -2.050034 -3.824986 90)
			(size 0.519938 1.4986)
			(layers "F.Cu" "F.Mask" "F.Paste")
			(net "GND")
		)
		(pad "72" smd rect
			(at -2.050034 -2.975102 90)
			(size 0.519938 1.4986)
			(layers "F.Cu" "F.Mask" "F.Paste")
			(net "M_H_CPU0_SA_CA<6>")
		)
		(pad "73" smd rect
			(at -2.050034 -2.124964 90)
			(size 0.519938 1.4986)
			(layers "F.Cu" "F.Mask" "F.Paste")
			(net "GND")
		)
		(pad "74" smd rect
			(at -2.050034 -1.27508 90)
			(size 0.519938 1.4986)
			(layers "F.Cu" "F.Mask" "F.Paste")
			(net "M_H_CPU0_SA_PAR")
		)
		(pad "75" smd rect
			(at -2.050034 -0.424942 90)
			(size 0.519938 1.4986)
			(layers "F.Cu" "F.Mask" "F.Paste")
			(net "GND")
		)
		(pad "76" smd rect
			(at -2.050034 5.525008 90)
			(size 0.519938 1.4986)
			(layers "F.Cu" "F.Mask" "F.Paste")
			(net "M_H_CPU0_SB_CA<0>")
		)
		(pad "77" smd rect
			(at -2.050034 6.374892 90)
			(size 0.519938 1.4986)
			(layers "F.Cu" "F.Mask" "F.Paste")
			(net "GND")
		)
		(pad "78" smd rect
			(at -2.050034 7.22503 90)
			(size 0.519938 1.4986)
			(layers "F.Cu" "F.Mask" "F.Paste")
			(net "M_H_CPU0_SB_CA<2>")
		)
		(pad "79" smd rect
			(at -2.050034 8.074914 90)
			(size 0.519938 1.4986)
			(layers "F.Cu" "F.Mask" "F.Paste")
			(net "GND")
		)
		(pad "80" smd rect
			(at -2.050034 8.925052 90)
			(size 0.519938 1.4986)
			(layers "F.Cu" "F.Mask" "F.Paste")
			(net "M_H_CPU0_SB_CA<4>")
		)
		(pad "81" smd rect
			(at -2.050034 9.774936 90)
			(size 0.519938 1.4986)
			(layers "F.Cu" "F.Mask" "F.Paste")
			(net "GND")
		)
		(pad "82" smd rect
			(at -2.050034 10.625074 90)
			(size 0.519938 1.4986)
			(layers "F.Cu" "F.Mask" "F.Paste")
			(net "M_H_CPU0_SB_CA<6>")
		)
		(pad "83" smd rect
			(at -2.050034 11.474958 90)
			(size 0.519938 1.4986)
			(layers "F.Cu" "F.Mask" "F.Paste")
			(net "GND")
		)
		(pad "84" smd rect
			(at -2.050034 12.325096 90)
			(size 0.519938 1.4986)
			(layers "F.Cu" "F.Mask" "F.Paste")
			(net "M_H_CPU0_SB_CS_N<0>")
		)
		(pad "85" smd rect
			(at -2.050034 13.17498 90)
			(size 0.519938 1.4986)
			(layers "F.Cu" "F.Mask" "F.Paste")
			(net "GND")
		)
		(pad "86" smd rect
			(at -2.050034 14.025118 90)
			(size 0.519938 1.4986)
			(layers "F.Cu" "F.Mask" "F.Paste")
			(net "M_H_CPU0_SA_RSP<0>")
		)
		(pad "87" smd rect
			(at -2.050034 14.875002 90)
			(size 0.519938 1.4986)
			(layers "F.Cu" "F.Mask" "F.Paste")
			(net "M_H_CPU0_SB_RSP<0>")
		)
		(pad "88" smd rect
			(at -2.050034 15.724886 90)
			(size 0.519938 1.4986)
			(layers "F.Cu" "F.Mask" "F.Paste")
			(net "GND")
		)
		(pad "89" smd rect
			(at -2.050034 16.575024 90)
			(size 0.519938 1.4986)
			(layers "F.Cu" "F.Mask" "F.Paste")
			(net "M_H_CPU0_SB_CB<4>")
		)
		(pad "90" smd rect
			(at -2.050034 17.424908 90)
			(size 0.519938 1.4986)
			(layers "F.Cu" "F.Mask" "F.Paste")
			(net "GND")
		)
		(pad "91" smd rect
			(at -2.050034 18.275046 90)
			(size 0.519938 1.4986)
			(layers "F.Cu" "F.Mask" "F.Paste")
			(net "M_H_CPU0_SB_CB<5>")
		)
		(pad "92" smd rect
			(at -2.050034 19.12493 90)
			(size 0.519938 1.4986)
			(layers "F.Cu" "F.Mask" "F.Paste")
			(net "GND")
		)
		(pad "93" smd rect
			(at -2.050034 19.975068 90)
			(size 0.519938 1.4986)
			(layers "F.Cu" "F.Mask" "F.Paste")
			(net "M_H_CPU0_SB_DQS_DP<9>")
		)
		(pad "94" smd rect
			(at -2.050034 20.824952 90)
			(size 0.519938 1.4986)
			(layers "F.Cu" "F.Mask" "F.Paste")
			(net "M_H_CPU0_SB_DQS_DN<9>")
		)
		(pad "95" smd rect
			(at -2.050034 21.67509 90)
			(size 0.519938 1.4986)
			(layers "F.Cu" "F.Mask" "F.Paste")
			(net "GND")
		)
		(pad "96" smd rect
			(at -2.050034 22.524974 90)
			(size 0.519938 1.4986)
			(layers "F.Cu" "F.Mask" "F.Paste")
			(net "M_H_CPU0_SB_CB<0>")
		)
		(pad "97" smd rect
			(at -2.050034 23.375112 90)
			(size 0.519938 1.4986)
			(layers "F.Cu" "F.Mask" "F.Paste")
			(net "GND")
		)
		(pad "98" smd rect
			(at -2.050034 24.224996 90)
			(size 0.519938 1.4986)
			(layers "F.Cu" "F.Mask" "F.Paste")
			(net "M_H_CPU0_SB_CB<1>")
		)
		(pad "99" smd rect
			(at -2.050034 25.07488 90)
			(size 0.519938 1.4986)
			(layers "F.Cu" "F.Mask" "F.Paste")
			(net "GND")
		)
		(pad "100" smd rect
			(at -2.050034 25.925018 90)
			(size 0.519938 1.4986)
			(layers "F.Cu" "F.Mask" "F.Paste")
			(net "M_H_CPU0_SB_DQ<0>")
		)
		(pad "101" smd rect
			(at -2.050034 26.774902 90)
			(size 0.519938 1.4986)
			(layers "F.Cu" "F.Mask" "F.Paste")
			(net "GND")
		)
		(pad "102" smd rect
			(at -2.050034 27.62504 90)
			(size 0.519938 1.4986)
			(layers "F.Cu" "F.Mask" "F.Paste")
			(net "M_H_CPU0_SB_DQ<1>")
		)
		(pad "103" smd rect
			(at -2.050034 28.474924 90)
			(size 0.519938 1.4986)
			(layers "F.Cu" "F.Mask" "F.Paste")
			(net "GND")
		)
		(pad "104" smd rect
			(at -2.050034 29.325062 90)
			(size 0.519938 1.4986)
			(layers "F.Cu" "F.Mask" "F.Paste")
			(net "M_H_CPU0_SB_DQS_DP<0>")
		)
		(pad "105" smd rect
			(at -2.050034 30.174946 90)
			(size 0.519938 1.4986)
			(layers "F.Cu" "F.Mask" "F.Paste")
			(net "M_H_CPU0_SB_DQS_DN<0>")
		)
		(pad "106" smd rect
			(at -2.050034 31.025084 90)
			(size 0.519938 1.4986)
			(layers "F.Cu" "F.Mask" "F.Paste")
			(net "GND")
		)
		(pad "107" smd rect
			(at -2.050034 31.874968 90)
			(size 0.519938 1.4986)
			(layers "F.Cu" "F.Mask" "F.Paste")
			(net "M_H_CPU0_SB_DQ<4>")
		)
		(pad "108" smd rect
			(at -2.050034 32.725106 90)
			(size 0.519938 1.4986)
			(layers "F.Cu" "F.Mask" "F.Paste")
			(net "GND")
		)
		(pad "109" smd rect
			(at -2.050034 33.57499 90)
			(size 0.519938 1.4986)
			(layers "F.Cu" "F.Mask" "F.Paste")
			(net "M_H_CPU0_SB_DQ<5>")
		)
		(pad "110" smd rect
			(at -2.050034 34.425128 90)
			(size 0.519938 1.4986)
			(layers "F.Cu" "F.Mask" "F.Paste")
			(net "GND")
		)
		(pad "111" smd rect
			(at -2.050034 35.275012 90)
			(size 0.519938 1.4986)
			(layers "F.Cu" "F.Mask" "F.Paste")
			(net "M_H_CPU0_SB_DQ<8>")
		)
		(pad "112" smd rect
			(at -2.050034 36.124896 90)
			(size 0.519938 1.4986)
			(layers "F.Cu" "F.Mask" "F.Paste")
			(net "GND")
		)
		(pad "113" smd rect
			(at -2.050034 36.975034 90)
			(size 0.519938 1.4986)
			(layers "F.Cu" "F.Mask" "F.Paste")
			(net "M_H_CPU0_SB_DQ<9>")
		)
	)
)
